# T6G (Grand Teton) — schematic netlist excerpt (pin names and nets, part order shuffled) for the footprints in the layout excerpt that follows; sources: Cadence DE-HDL packaged netlist, KiCad conversion of 04192023_DAF0TMB3IC0_F0TG_MB_C_brd_V02_OCP.brd

PC6900  Q_CAP  22UF 16V 20% X6S  pkg C0805  page 360 : A = SW_P12V_AUX_P1V8_RETIMER_CPU0_FLT ; B = GND
R4215  Q_RES  0 5% CHIP  pkg 0402LF  page 235 : A = FM_THERMAL_ALERT_N ; B = FM_G751_0_ALERT_N
PR4001  Q_RES  6.8K 1% CHIP  pkg 0402LF  page 152 : A = P12V_SCM_UV ; B = P12V_SCM_OV

(kicad_pcb
	(version 20260206)
	(generator "pcbnew")
	(generator_version "10.0")
	(general
		(thickness 1.6)
		(legacy_teardrops no)
	)
	(paper "A4")
	(title_block
		(title "04192023_DAF0TMB3IC0_F0TG_MB_C_brd_V02_OCP.brd")
		(comment 1 "Grand Teton / footprints 3392-3394 of 8354")
	)
	(layers
		(0 "F.Cu" signal "TOP")
		(4 "In1.Cu" signal "GND")
		(6 "In2.Cu" signal "IN1")
		(8 "In3.Cu" signal "GND1")
		(10 "In4.Cu" signal "IN2")
		(12 "In5.Cu" signal "GND2")
		(14 "In6.Cu" signal "IN3")
		(16 "In7.Cu" signal "GND3")
		(18 "In8.Cu" signal "VCC")
		(20 "In9.Cu" signal "VCC1")
		(22 "In10.Cu" signal "GND4")
		(24 "In11.Cu" signal "IN4")
		(26 "In12.Cu" signal "GND5")
		(28 "In13.Cu" signal "IN5")
		(30 "In14.Cu" signal "GND6")
		(32 "In15.Cu" signal "IN6")
		(34 "In16.Cu" signal "GND7")
		(2 "B.Cu" signal "BOTTOM")
		(9 "F.Adhes" user "F.Adhesive")
		(11 "B.Adhes" user "B.Adhesive")
		(13 "F.Paste" user "Package Geometry/Pastemask Top")
		(15 "B.Paste" user "Package Geometry/Pastemask Bottom")
		(5 "F.SilkS" user "Ref Des/Silkscreen Top")
		(7 "B.SilkS" user "Ref Des/Silkscreen Bottom")
		(1 "F.Mask" user "Board Geometry/Soldermask Top")
		(3 "B.Mask" user "Board Geometry/Soldermask Bottom")
		(17 "Dwgs.User" user "User.Drawings")
		(19 "Cmts.User" user "User.Comments")
		(21 "Eco1.User" user "User.Eco1")
		(23 "Eco2.User" user "User.Eco2")
		(25 "Edge.Cuts" user "Board Geometry/Outline")
		(27 "Margin" user)
		(31 "F.CrtYd" user "Package Geometry/Place Bound Top")
		(29 "B.CrtYd" user "Package Geometry/Place Bound Bottom")
		(35 "F.Fab" user "Ref Des/Assembly Top")
		(33 "B.Fab" user "Ref Des/Assembly Bottom")
	)
	(footprint ""
		(layer "F.Cu")
		(at 240.792 -285.2928 180)
		(property "Reference" "PC6900"
			(at 0 0 180)
			(layer "F.SilkS")
			(hide yes)
			(effects
				(font
					(size 1.27 1.27)
				)
			)
		)
		(property "Value" ""
			(at 0 0 180)
			(layer "F.Fab")
			(effects
				(font
					(size 1.27 1.27)
				)
			)
		)
		(duplicate_pad_numbers_are_jumpers no)
		(fp_line
			(start 1.524 0.762)
			(end -1.524 0.762)
			(stroke
				(width 0.1524)
				(type default)
			)
			(layer "F.SilkS")
		)
		(fp_line
			(start 1.524 -0.762)
			(end 1.524 0.762)
			(stroke
				(width 0.1524)
				(type default)
			)
			(layer "F.SilkS")
		)
		(fp_line
			(start -1.524 0.762)
			(end -1.524 -0.762)
			(stroke
				(width 0.1524)
				(type default)
			)
			(layer "F.SilkS")
		)
		(fp_line
			(start -1.524 -0.762)
			(end 1.524 -0.762)
			(stroke
				(width 0.1524)
				(type default)
			)
			(layer "F.SilkS")
		)
		(fp_line
			(start 1.1049 0.724916)
			(end 1.1049 -0.724916)
			(stroke
				(width 0.1)
				(type default)
			)
			(layer "F.Fab")
		)
		(fp_line
			(start 1.1049 -0.724916)
			(end -1.1049 -0.724916)
			(stroke
				(width 0.1)
				(type default)
			)
			(layer "F.Fab")
		)
		(fp_line
			(start -1.1049 0.724916)
			(end 1.1049 0.724916)
			(stroke
				(width 0.1)
				(type default)
			)
			(layer "F.Fab")
		)
		(fp_line
			(start -1.1049 -0.724916)
			(end -1.1049 0.724916)
			(stroke
				(width 0.1)
				(type default)
			)
			(layer "F.Fab")
		)
		(pad "1" smd rect
			(at -0.889 0)
			(size 1.016 1.27)
			(layers "F.Cu" "F.Mask" "F.Paste")
			(net "SW_P12V_AUX_P1V8_RETIMER_CPU0_FLT")
		)
		(pad "2" smd rect
			(at 0.889 0)
			(size 1.016 1.27)
			(layers "F.Cu" "F.Mask" "F.Paste")
			(net "GND")
		)
	)
	(footprint ""
		(layer "F.Cu")
		(at 187.221622 -22.727158 -90)
		(property "Reference" "PR4001"
			(at 0 0 270)
			(layer "F.SilkS")
			(hide yes)
			(effects
				(font
					(size 1.27 1.27)
				)
			)
		)
		(property "Value" ""
			(at 0 0 270)
			(layer "F.Fab")
			(effects
				(font
					(size 1.27 1.27)
				)
			)
		)
		(duplicate_pad_numbers_are_jumpers no)
		(fp_line
			(start -0.7874 0.4064)
			(end -0.7874 -0.4064)
			(stroke
				(width 0.1524)
				(type default)
			)
			(layer "F.SilkS")
		)
		(fp_line
			(start 0.7874 0.4064)
			(end -0.7874 0.4064)
			(stroke
				(width 0.1524)
				(type default)
			)
			(layer "F.SilkS")
		)
		(fp_line
			(start -0.7874 -0.4064)
			(end 0.7874 -0.4064)
			(stroke
				(width 0.1524)
				(type default)
			)
			(layer "F.SilkS")
		)
		(fp_line
			(start 0.7874 -0.4064)
			(end 0.7874 0.4064)
			(stroke
				(width 0.1524)
				(type default)
			)
			(layer "F.SilkS")
		)
		(fp_line
			(start -0.67945 0.3048)
			(end -0.67945 -0.305054)
			(stroke
				(width 0.1)
				(type default)
			)
			(layer "F.Fab")
		)
		(fp_line
			(start -0.12065 0.3048)
			(end -0.67945 0.3048)
			(stroke
				(width 0.1)
				(type default)
			)
			(layer "F.Fab")
		)
		(fp_line
			(start 0.120396 0.3048)
			(end 0.120396 0.2794)
			(stroke
				(width 0.1)
				(type default)
			)
			(layer "F.Fab")
		)
		(fp_line
			(start 0.67945 0.3048)
			(end 0.120396 0.3048)
			(stroke
				(width 0.1)
				(type default)
			)
			(layer "F.Fab")
		)
		(fp_line
			(start -0.12065 0.2794)
			(end -0.12065 0.3048)
			(stroke
				(width 0.1)
				(type default)
			)
			(layer "F.Fab")
		)
		(fp_line
			(start 0.120396 0.2794)
			(end -0.12065 0.2794)
			(stroke
				(width 0.1)
				(type default)
			)
			(layer "F.Fab")
		)
		(fp_line
			(start -0.12065 -0.2794)
			(end 0.12065 -0.2794)
			(stroke
				(width 0.1)
				(type default)
			)
			(layer "F.Fab")
		)
		(fp_line
			(start 0.12065 -0.2794)
			(end 0.12065 -0.3048)
			(stroke
				(width 0.1)
				(type default)
			)
			(layer "F.Fab")
		)
		(fp_line
			(start 0.12065 -0.3048)
			(end 0.67945 -0.3048)
			(stroke
				(width 0.1)
				(type default)
			)
			(layer "F.Fab")
		)
		(fp_line
			(start 0.67945 -0.3048)
			(end 0.67945 0.3048)
			(stroke
				(width 0.1)
				(type default)
			)
			(layer "F.Fab")
		)
		(fp_line
			(start -0.67945 -0.305054)
			(end -0.12065 -0.305054)
			(stroke
				(width 0.1)
				(type default)
			)
			(layer "F.Fab")
		)
		(fp_line
			(start -0.12065 -0.305054)
			(end -0.12065 -0.2794)
			(stroke
				(width 0.1)
				(type default)
			)
			(layer "F.Fab")
		)
		(pad "1" smd circle
			(at -0.40005 0 270)
			(size 0 0)
			(layers "F.Cu" "F.Mask" "F.Paste")
			(net "P12V_SCM_UV")
		)
		(pad "2" smd circle
			(at 0.40005 0 270)
			(size 0 0)
			(layers "F.Cu" "F.Mask" "F.Paste")
			(net "P12V_SCM_OV")
		)
	)
	(footprint ""
		(layer "F.Cu")
		(at 368.427 -413.639 90)
		(property "Reference" "R4215"
			(at 0 0 90)
			(layer "F.SilkS")
			(hide yes)
			(effects
				(font
					(size 1.27 1.27)
				)
			)
		)
		(property "Value" ""
			(at 0 0 90)
			(layer "F.Fab")
			(effects
				(font
					(size 1.27 1.27)
				)
			)
		)
		(duplicate_pad_numbers_are_jumpers no)
		(fp_line
			(start 0.7874 -0.4064)
			(end 0.7874 0.4064)
			(stroke
				(width 0.1524)
				(type default)
			)
			(layer "F.SilkS")
		)
		(fp_line
			(start -0.7874 -0.4064)
			(end 0.7874 -0.4064)
			(stroke
				(width 0.1524)
				(type default)
			)
			(layer "F.SilkS")
		)
		(fp_line
			(start 0.7874 0.4064)
			(end -0.7874 0.4064)
			(stroke
				(width 0.1524)
				(type default)
			)
			(layer "F.SilkS")
		)
		(fp_line
			(start -0.7874 0.4064)
			(end -0.7874 -0.4064)
			(stroke
				(width 0.1524)
				(type default)
			)
			(layer "F.SilkS")
		)
		(fp_line
			(start -0.12065 -0.305054)
			(end -0.12065 -0.2794)
			(stroke
				(width 0.1)
				(type default)
			)
			(layer "F.Fab")
		)
		(fp_line
			(start -0.67945 -0.305054)
			(end -0.12065 -0.305054)
			(stroke
				(width 0.1)
				(type default)
			)
			(layer "F.Fab")
		)
		(fp_line
			(start 0.67945 -0.3048)
			(end 0.67945 0.3048)
			(stroke
				(width 0.1)
				(type default)
			)
			(layer "F.Fab")
		)
		(fp_line
			(start 0.12065 -0.3048)
			(end 0.67945 -0.3048)
			(stroke
				(width 0.1)
				(type default)
			)
			(layer "F.Fab")
		)
		(fp_line
			(start 0.12065 -0.2794)
			(end 0.12065 -0.3048)
			(stroke
				(width 0.1)
				(type default)
			)
			(layer "F.Fab")
		)
		(fp_line
			(start -0.12065 -0.2794)
			(end 0.12065 -0.2794)
			(stroke
				(width 0.1)
				(type default)
			)
			(layer "F.Fab")
		)
		(fp_line
			(start 0.120396 0.2794)
			(end -0.12065 0.2794)
			(stroke
				(width 0.1)
				(type default)
			)
			(layer "F.Fab")
		)
		(fp_line
			(start -0.12065 0.2794)
			(end -0.12065 0.3048)
			(stroke
				(width 0.1)
				(type default)
			)
			(layer "F.Fab")
		)
		(fp_line
			(start 0.67945 0.3048)
			(end 0.120396 0.3048)
			(stroke
				(width 0.1)
				(type default)
			)
			(layer "F.Fab")
		)
		(fp_line
			(start 0.120396 0.3048)
			(end 0.120396 0.2794)
			(stroke
				(width 0.1)
				(type default)
			)
			(layer "F.Fab")
		)
		(fp_line
			(start -0.12065 0.3048)
			(end -0.67945 0.3048)
			(stroke
				(width 0.1)
				(type default)
			)
			(layer "F.Fab")
		)
		(fp_line
			(start -0.67945 0.3048)
			(end -0.67945 -0.305054)
			(stroke
				(width 0.1)
				(type default)
			)
			(layer "F.Fab")
		)
		(pad "1" smd circle
			(at -0.40005 0 90)
			(size 0 0)
			(layers "F.Cu" "F.Mask" "F.Paste")
			(net "FM_THERMAL_ALERT_N")
		)
		(pad "2" smd circle
			(at 0.40005 0 90)
			(size 0 0)
			(layers "F.Cu" "F.Mask" "F.Paste")
			(net "FM_G751_0_ALERT_N")
		)
	)
)
